# BASEBOARD_FAB2 (Tioga Pass) — schematic netlist excerpt (pin names and nets, part order shuffled) for the footprints in the layout excerpt that follows; sources: Cadence DE-HDL packaged netlist, KiCad conversion of Wiwynn_Tioga_Pass_MB.brd

R7F29  RES  33.2 1% CHIP  pkg 0402  page 153 : A = SPI_SWITCH_MOSI ; B = SPI_SWITCH_MOSI_R0
R8A11  RES  22.1 1.0% CHIP  pkg 0402  page 237 : A = PWRGD_P1V8_PCH_STBY_R ; B = PWRGD_P1V8_PCH_STBY
C7G12  CAP  0.22UF 16V 10% X7R  pkg 0402  page 105 : A = P3E_CPU0_PE2_SS_TXN<12> ; B = P3E_CPU0_PE2_SS_C_TXN<12>

(kicad_pcb
	(version 20260206)
	(generator "pcbnew")
	(generator_version "10.0")
	(general
		(thickness 1.6)
		(legacy_teardrops no)
	)
	(paper "A4")
	(title_block
		(title "Wiwynn_Tioga_Pass_MB.brd")
		(comment 1 "Tioga Pass / footprints 328-330 of 4770")
	)
	(layers
		(0 "F.Cu" signal "TOP")
		(4 "In1.Cu" signal "L2GND")
		(6 "In2.Cu" signal "L3")
		(8 "In3.Cu" signal "L4GND")
		(10 "In4.Cu" signal "L5")
		(12 "In5.Cu" signal "L6GND")
		(14 "In6.Cu" signal "L7VCC")
		(16 "In7.Cu" signal "L8VCC")
		(18 "In8.Cu" signal "L9GND")
		(20 "In9.Cu" signal "L10")
		(22 "In10.Cu" signal "L11GND")
		(24 "In11.Cu" signal "L12")
		(26 "In12.Cu" signal "L13GND")
		(2 "B.Cu" signal "BOTTOM")
		(9 "F.Adhes" user "F.Adhesive")
		(11 "B.Adhes" user "B.Adhesive")
		(13 "F.Paste" user "Package Geometry/Pastemask Top")
		(15 "B.Paste" user "Package Geometry/Pastemask Bottom")
		(5 "F.SilkS" user "Ref Des/Silkscreen Top")
		(7 "B.SilkS" user "Ref Des/Silkscreen Bottom")
		(1 "F.Mask" user "Board Geometry/Soldermask Top")
		(3 "B.Mask" user "Board Geometry/Soldermask Bottom")
		(17 "Dwgs.User" user "User.Drawings")
		(19 "Cmts.User" user "User.Comments")
		(21 "Eco1.User" user "User.Eco1")
		(23 "Eco2.User" user "User.Eco2")
		(25 "Edge.Cuts" user "Board Geometry/Outline")
		(27 "Margin" user)
		(31 "F.CrtYd" user "Package Geometry/Place Bound Top")
		(29 "B.CrtYd" user "Package Geometry/Place Bound Bottom")
		(35 "F.Fab" user "Ref Des/Assembly Top")
		(33 "B.Fab" user "Ref Des/Assembly Bottom")
	)
	(footprint ""
		(layer "F.Cu")
		(at 385.8768 -51.6128 180)
		(property "Reference" "R7F29"
			(at 0 0 180)
			(layer "F.SilkS")
			(hide yes)
			(effects
				(font
					(size 1.27 1.27)
				)
			)
		)
		(property "Value" ""
			(at 0 0 180)
			(layer "F.Fab")
			(effects
				(font
					(size 1.27 1.27)
				)
			)
		)
		(duplicate_pad_numbers_are_jumpers no)
		(fp_poly
			(pts
				(xy -0.2794 -0.1016) (xy 0.2794 -0.1016) (xy 0.2794 0.9906) (xy -0.2794 0.9906)
			)
			(stroke
				(width 0)
				(type default)
			)
			(fill no)
			(layer "F.CrtYd")
		)
		(fp_line
			(start 0.2794 0.9906)
			(end 0.2794 -0.1016)
			(stroke
				(width 0.1)
				(type default)
			)
			(layer "F.Fab")
		)
		(fp_line
			(start 0.2794 -0.1016)
			(end -0.2794 -0.1016)
			(stroke
				(width 0.1)
				(type default)
			)
			(layer "F.Fab")
		)
		(fp_line
			(start -0.2794 0.9906)
			(end 0.2794 0.9906)
			(stroke
				(width 0.1)
				(type default)
			)
			(layer "F.Fab")
		)
		(fp_line
			(start -0.2794 -0.1016)
			(end -0.2794 0.9906)
			(stroke
				(width 0.1)
				(type default)
			)
			(layer "F.Fab")
		)
		(pad "1" smd rect
			(at 0 0 180)
			(size 0.508 0.508)
			(layers "F.Cu" "F.Mask" "F.Paste")
			(net "SPI_SWITCH_MOSI")
		)
		(pad "2" smd rect
			(at 0 0.889 180)
			(size 0.508 0.508)
			(layers "F.Cu" "F.Mask" "F.Paste")
			(net "SPI_SWITCH_MOSI_R0")
		)
		(zone
			(layer "F.Cu")
			(hatch none 0.5)
			(connect_pads
				(clearance 0)
			)
			(min_thickness 0.25)
			(keepout
				(tracks not_allowed)
				(vias allowed)
				(pads allowed)
				(copperpour not_allowed)
				(footprints allowed)
			)
			(placement
				(enabled no)
				(sheetname "")
			)
			(fill
				(thermal_gap 0.5)
				(thermal_bridge_width 0.5)
				(island_removal_mode 0)
			)
			(polygon
				(pts
					(xy 386.1308 -52.2478) (xy 385.6228 -52.2478) (xy 385.6228 -51.8668) (xy 386.1308 -51.8668)
				)
			)
		)
		(zone
			(layer "F.Cu")
			(hatch none 0.5)
			(connect_pads
				(clearance 0)
			)
			(min_thickness 0.25)
			(keepout
				(tracks allowed)
				(vias not_allowed)
				(pads allowed)
				(copperpour not_allowed)
				(footprints allowed)
			)
			(placement
				(enabled no)
				(sheetname "")
			)
			(fill
				(thermal_gap 0.5)
				(thermal_bridge_width 0.5)
				(island_removal_mode 0)
			)
			(polygon
				(pts
					(xy 386.1308 -51.8668) (xy 385.6228 -51.8668) (xy 385.6228 -52.2478) (xy 386.1308 -52.2478)
				)
			)
		)
	)
	(footprint ""
		(layer "F.Cu")
		(at 370.366544 -10.916158)
		(property "Reference" "C7G12"
			(at 0 0 0)
			(layer "F.SilkS")
			(hide yes)
			(effects
				(font
					(size 1.27 1.27)
				)
			)
		)
		(property "Value" ""
			(at 0 0 0)
			(layer "F.Fab")
			(effects
				(font
					(size 1.27 1.27)
				)
			)
		)
		(duplicate_pad_numbers_are_jumpers no)
		(fp_rect
			(start -0.3048 0.9906)
			(end 0.3048 -0.1016)
			(stroke
				(width 0)
				(type default)
			)
			(fill no)
			(layer "F.CrtYd")
		)
		(fp_line
			(start -0.3048 -0.1016)
			(end -0.3048 0.9906)
			(stroke
				(width 0.1)
				(type default)
			)
			(layer "F.Fab")
		)
		(fp_line
			(start -0.3048 0.9906)
			(end 0.3048 0.9906)
			(stroke
				(width 0.1)
				(type default)
			)
			(layer "F.Fab")
		)
		(fp_line
			(start 0.3048 -0.1016)
			(end -0.3048 -0.1016)
			(stroke
				(width 0.1)
				(type default)
			)
			(layer "F.Fab")
		)
		(fp_line
			(start 0.3048 0.9906)
			(end 0.3048 -0.1016)
			(stroke
				(width 0.1)
				(type default)
			)
			(layer "F.Fab")
		)
		(pad "1" smd rect
			(at 0 0)
			(size 0.508 0.508)
			(layers "F.Cu" "F.Mask" "F.Paste")
			(net "P3E_CPU0_PE2_SS_TXN<12>")
		)
		(pad "2" smd rect
			(at 0 0.889)
			(size 0.508 0.508)
			(layers "F.Cu" "F.Mask" "F.Paste")
			(net "P3E_CPU0_PE2_SS_C_TXN<12>")
		)
		(zone
			(layer "F.Cu")
			(hatch none 0.5)
			(connect_pads
				(clearance 0)
			)
			(min_thickness 0.25)
			(keepout
				(tracks not_allowed)
				(vias allowed)
				(pads allowed)
				(copperpour not_allowed)
				(footprints allowed)
			)
			(placement
				(enabled no)
				(sheetname "")
			)
			(fill
				(thermal_gap 0.5)
				(thermal_bridge_width 0.5)
				(island_removal_mode 0)
			)
			(polygon
				(pts
					(xy 370.112544 -10.281158) (xy 370.620544 -10.281158) (xy 370.620544 -10.662158) (xy 370.112544 -10.662158)
				)
			)
		)
		(zone
			(layer "F.Cu")
			(hatch none 0.5)
			(connect_pads
				(clearance 0)
			)
			(min_thickness 0.25)
			(keepout
				(tracks allowed)
				(vias not_allowed)
				(pads allowed)
				(copperpour not_allowed)
				(footprints allowed)
			)
			(placement
				(enabled no)
				(sheetname "")
			)
			(fill
				(thermal_gap 0.5)
				(thermal_bridge_width 0.5)
				(island_removal_mode 0)
			)
			(polygon
				(pts
					(xy 370.112544 -10.281158) (xy 370.620544 -10.281158) (xy 370.620544 -10.662158) (xy 370.112544 -10.662158)
				)
			)
		)
	)
	(footprint ""
		(layer "F.Cu")
		(at 405.283416 -147.420584 90)
		(property "Reference" "R8A11"
			(at 0 0 90)
			(layer "F.SilkS")
			(hide yes)
			(effects
				(font
					(size 1.27 1.27)
				)
			)
		)
		(property "Value" ""
			(at 0 0 90)
			(layer "F.Fab")
			(effects
				(font
					(size 1.27 1.27)
				)
			)
		)
		(duplicate_pad_numbers_are_jumpers no)
		(fp_poly
			(pts
				(xy -0.2794 -0.1016) (xy 0.2794 -0.1016) (xy 0.2794 0.9906) (xy -0.2794 0.9906)
			)
			(stroke
				(width 0)
				(type default)
			)
			(fill no)
			(layer "F.CrtYd")
		)
		(fp_line
			(start 0.2794 -0.1016)
			(end -0.2794 -0.1016)
			(stroke
				(width 0.1)
				(type default)
			)
			(layer "F.Fab")
		)
		(fp_line
			(start -0.2794 -0.1016)
			(end -0.2794 0.9906)
			(stroke
				(width 0.1)
				(type default)
			)
			(layer "F.Fab")
		)
		(fp_line
			(start 0.2794 0.9906)
			(end 0.2794 -0.1016)
			(stroke
				(width 0.1)
				(type default)
			)
			(layer "F.Fab")
		)
		(fp_line
			(start -0.2794 0.9906)
			(end 0.2794 0.9906)
			(stroke
				(width 0.1)
				(type default)
			)
			(layer "F.Fab")
		)
		(pad "1" smd rect
			(at 0 0 90)
			(size 0.508 0.508)
			(layers "F.Cu" "F.Mask" "F.Paste")
			(net "PWRGD_P1V8_PCH_STBY_R")
		)
		(pad "2" smd rect
			(at 0 0.889 90)
			(size 0.508 0.508)
			(layers "F.Cu" "F.Mask" "F.Paste")
			(net "PWRGD_P1V8_PCH_STBY")
		)
		(zone
			(layer "F.Cu")
			(hatch none 0.5)
			(connect_pads
				(clearance 0)
			)
			(min_thickness 0.25)
			(keepout
				(tracks allowed)
				(vias not_allowed)
				(pads allowed)
				(copperpour not_allowed)
				(footprints allowed)
			)
			(placement
				(enabled no)
				(sheetname "")
			)
			(fill
				(thermal_gap 0.5)
				(thermal_bridge_width 0.5)
				(island_removal_mode 0)
			)
			(polygon
				(pts
					(xy 405.537416 -147.166584) (xy 405.537416 -147.674584) (xy 405.918416 -147.674584) (xy 405.918416 -147.166584)
				)
			)
		)
		(zone
			(layer "F.Cu")
			(hatch none 0.5)
			(connect_pads
				(clearance 0)
			)
			(min_thickness 0.25)
			(keepout
				(tracks not_allowed)
				(vias allowed)
				(pads allowed)
				(copperpour not_allowed)
				(footprints allowed)
			)
			(placement
				(enabled no)
				(sheetname "")
			)
			(fill
				(thermal_gap 0.5)
				(thermal_bridge_width 0.5)
				(island_removal_mode 0)
			)
			(polygon
				(pts
					(xy 405.918416 -147.166584) (xy 405.918416 -147.674584) (xy 405.537416 -147.674584) (xy 405.537416 -147.166584)
				)
			)
		)
	)
)
